(kicad_pcb
	(version 20260206)
	(generator "pcbnew")
	(generator_version "10.0")
	(general
		(thickness 1.6)
		(legacy_teardrops no)
	)
	(paper "A4")
	(title_block
		(title "baseboard — 13948-1b.1110WZS1818.brd")
		(comment 1 "Honey Badger (Wiwynn) / footprints 1953-1960 of 2523")
	)
	(layers
		(0 "F.Cu" signal "TOP")
		(4 "In1.Cu" signal "L2GND")
		(6 "In2.Cu" signal "L3")
		(8 "In3.Cu" signal "L4VCC")
		(10 "In4.Cu" signal "L5VCC")
		(12 "In5.Cu" signal "L6")
		(14 "In6.Cu" signal "L7GND")
		(2 "B.Cu" signal "BOTTOM")
		(9 "F.Adhes" user "F.Adhesive")
		(11 "B.Adhes" user "B.Adhesive")
		(13 "F.Paste" user "Package Geometry/Pastemask Top")
		(15 "B.Paste" user "Package Geometry/Pastemask Bottom")
		(5 "F.SilkS" user "Ref Des/Silkscreen Top")
		(7 "B.SilkS" user "Ref Des/Silkscreen Bottom")
		(1 "F.Mask" user "Board Geometry/Soldermask Top")
		(3 "B.Mask" user "Board Geometry/Soldermask Bottom")
		(17 "Dwgs.User" user "User.Drawings")
		(19 "Cmts.User" user "User.Comments")
		(21 "Eco1.User" user "User.Eco1")
		(23 "Eco2.User" user "User.Eco2")
		(25 "Edge.Cuts" user "Board Geometry/Outline")
		(27 "Margin" user)
		(31 "F.CrtYd" user "Package Geometry/Place Bound Top")
		(29 "B.CrtYd" user "Package Geometry/Place Bound Bottom")
		(35 "F.Fab" user "Ref Des/Assembly Top")
		(33 "B.Fab" user "Ref Des/Assembly Bottom")
	)
	(footprint ""
		(layer "B.Cu")
		(at 24.596344 -176.276762 90)
		(property "Reference" "SC1112"
			(at 0 0 90)
			(layer "B.SilkS")
			(hide yes)
			(effects
				(font
					(size 1.27 1.27)
				)
				(justify mirror)
			)
		)
		(property "Value" "SCD1U16V2KX-3GP"
			(at -1.1811 -2.7051 90)
			(unlocked yes)
			(layer "B.Fab")
			(hide yes)
			(effects
				(font
					(size 1.016 1.016)
					(thickness 0.1524)
				)
				(justify mirror)
			)
		)
		(property "Device Type" "C402H22"
			(at -1.1811 -4.2291 90)
			(unlocked yes)
			(layer "B.Fab")
			(hide yes)
			(effects
				(font
					(size 1.016 1.016)
					(thickness 0.1524)
				)
				(justify mirror)
			)
		)
		(duplicate_pad_numbers_are_jumpers no)
		(fp_rect
			(start 0.4318 0.9525)
			(end -0.4318 -0.9525)
			(stroke
				(width 0)
				(type default)
			)
			(fill no)
			(layer "B.CrtYd")
		)
		(fp_rect
			(start 0.4318 0.9525)
			(end -0.4318 -0.9525)
			(stroke
				(width 0)
				(type default)
			)
			(fill no)
			(layer "B.Fab")
		)
		(pad "1" smd custom
			(at 0 -0.4445 270)
			(size 0.1524 0.1524)
			(layers "B.Cu" "B.Mask" "B.Paste")
			(net "P3V3_STBY")
			(options
				(clearance outline)
				(anchor circle)
			)
			(primitives
				(gr_poly
					(pts
						(arc
							(start 0.3048 0.2032)
							(mid 0.275042 0.275042)
							(end 0.2032 0.3048)
						)
						(arc
							(start -0.2032 0.3048)
							(mid -0.275042 0.275042)
							(end -0.3048 0.2032)
						)
						(arc
							(start -0.3048 -0.2032)
							(mid -0.275042 -0.275042)
							(end -0.2032 -0.3048)
						)
						(arc
							(start 0.2032 -0.3048)
							(mid 0.275042 -0.275042)
							(end 0.3048 -0.2032)
						)
					)
					(width 0)
					(fill yes)
				)
			)
		)
		(pad "2" smd custom
			(at 0 0.4445 270)
			(size 0.1524 0.1524)
			(layers "B.Cu" "B.Mask" "B.Paste")
			(net "GND")
			(options
				(clearance outline)
				(anchor circle)
			)
			(primitives
				(gr_poly
					(pts
						(arc
							(start 0.3048 0.2032)
							(mid 0.275042 0.275042)
							(end 0.2032 0.3048)
						)
						(arc
							(start -0.2032 0.3048)
							(mid -0.275042 0.275042)
							(end -0.3048 0.2032)
						)
						(arc
							(start -0.3048 -0.2032)
							(mid -0.275042 -0.275042)
							(end -0.2032 -0.3048)
						)
						(arc
							(start 0.2032 -0.3048)
							(mid 0.275042 -0.275042)
							(end 0.3048 -0.2032)
						)
					)
					(width 0)
					(fill yes)
				)
			)
		)
	)
	(footprint ""
		(layer "B.Cu")
		(at 180.013864 -33.854136 90)
		(property "Reference" "C230"
			(at 0 0 90)
			(layer "B.SilkS")
			(hide yes)
			(effects
				(font
					(size 1.27 1.27)
				)
				(justify mirror)
			)
		)
		(property "Value" "SCD1U16V2KX-3GP"
			(at -1.1811 -2.7051 90)
			(unlocked yes)
			(layer "B.Fab")
			(hide yes)
			(effects
				(font
					(size 1.016 1.016)
					(thickness 0.1524)
				)
				(justify mirror)
			)
		)
		(property "Device Type" "C402H22"
			(at -1.1811 -4.2291 90)
			(unlocked yes)
			(layer "B.Fab")
			(hide yes)
			(effects
				(font
					(size 1.016 1.016)
					(thickness 0.1524)
				)
				(justify mirror)
			)
		)
		(duplicate_pad_numbers_are_jumpers no)
		(fp_rect
			(start 0.4318 0.9525)
			(end -0.4318 -0.9525)
			(stroke
				(width 0)
				(type default)
			)
			(fill no)
			(layer "B.CrtYd")
		)
		(fp_rect
			(start 0.4318 0.9525)
			(end -0.4318 -0.9525)
			(stroke
				(width 0)
				(type default)
			)
			(fill no)
			(layer "B.Fab")
		)
		(pad "1" smd custom
			(at 0 -0.4445 270)
			(size 0.1524 0.1524)
			(layers "B.Cu" "B.Mask" "B.Paste")
			(net "P3V3_STBY")
			(options
				(clearance outline)
				(anchor circle)
			)
			(primitives
				(gr_poly
					(pts
						(arc
							(start 0.3048 0.2032)
							(mid 0.275042 0.275042)
							(end 0.2032 0.3048)
						)
						(arc
							(start -0.2032 0.3048)
							(mid -0.275042 0.275042)
							(end -0.3048 0.2032)
						)
						(arc
							(start -0.3048 -0.2032)
							(mid -0.275042 -0.275042)
							(end -0.2032 -0.3048)
						)
						(arc
							(start 0.2032 -0.3048)
							(mid 0.275042 -0.275042)
							(end 0.3048 -0.2032)
						)
					)
					(width 0)
					(fill yes)
				)
			)
		)
		(pad "2" smd custom
			(at 0 0.4445 270)
			(size 0.1524 0.1524)
			(layers "B.Cu" "B.Mask" "B.Paste")
			(net "GND")
			(options
				(clearance outline)
				(anchor circle)
			)
			(primitives
				(gr_poly
					(pts
						(arc
							(start 0.3048 0.2032)
							(mid 0.275042 0.275042)
							(end 0.2032 0.3048)
						)
						(arc
							(start -0.2032 0.3048)
							(mid -0.275042 0.275042)
							(end -0.3048 0.2032)
						)
						(arc
							(start -0.3048 -0.2032)
							(mid -0.275042 -0.275042)
							(end -0.2032 -0.3048)
						)
						(arc
							(start 0.2032 -0.3048)
							(mid 0.275042 -0.275042)
							(end 0.3048 -0.2032)
						)
					)
					(width 0)
					(fill yes)
				)
			)
		)
	)
	(footprint ""
		(layer "B.Cu")
		(at 98.787966 -43.307 -90)
		(property "Reference" "SC1030"
			(at 0 0 90)
			(layer "B.SilkS")
			(hide yes)
			(effects
				(font
					(size 1.27 1.27)
				)
				(justify mirror)
			)
		)
		(property "Value" "SC1KP50V2KX-1GP"
			(at -1.1811 -2.7051 270)
			(unlocked yes)
			(layer "B.Fab")
			(hide yes)
			(effects
				(font
					(size 1.016 1.016)
					(thickness 0.1524)
				)
				(justify mirror)
			)
		)
		(property "Device Type" "C402H22"
			(at -1.1811 -4.2291 270)
			(unlocked yes)
			(layer "B.Fab")
			(hide yes)
			(effects
				(font
					(size 1.016 1.016)
					(thickness 0.1524)
				)
				(justify mirror)
			)
		)
		(duplicate_pad_numbers_are_jumpers no)
		(fp_rect
			(start 0.4318 0.9525)
			(end -0.4318 -0.9525)
			(stroke
				(width 0)
				(type default)
			)
			(fill no)
			(layer "B.CrtYd")
		)
		(fp_rect
			(start 0.4318 0.9525)
			(end -0.4318 -0.9525)
			(stroke
				(width 0)
				(type default)
			)
			(fill no)
			(layer "B.Fab")
		)
		(pad "1" smd custom
			(at 0 -0.4445 90)
			(size 0.1524 0.1524)
			(layers "B.Cu" "B.Mask" "B.Paste")
			(net "P0V955_C")
			(options
				(clearance outline)
				(anchor circle)
			)
			(primitives
				(gr_poly
					(pts
						(arc
							(start 0.3048 0.2032)
							(mid 0.275042 0.275042)
							(end 0.2032 0.3048)
						)
						(arc
							(start -0.2032 0.3048)
							(mid -0.275042 0.275042)
							(end -0.3048 0.2032)
						)
						(arc
							(start -0.3048 -0.2032)
							(mid -0.275042 -0.275042)
							(end -0.2032 -0.3048)
						)
						(arc
							(start 0.2032 -0.3048)
							(mid 0.275042 -0.275042)
							(end 0.3048 -0.2032)
						)
					)
					(width 0)
					(fill yes)
				)
			)
		)
		(pad "2" smd custom
			(at 0 0.4445 90)
			(size 0.1524 0.1524)
			(layers "B.Cu" "B.Mask" "B.Paste")
			(net "GND")
			(options
				(clearance outline)
				(anchor circle)
			)
			(primitives
				(gr_poly
					(pts
						(arc
							(start 0.3048 0.2032)
							(mid 0.275042 0.275042)
							(end 0.2032 0.3048)
						)
						(arc
							(start -0.2032 0.3048)
							(mid -0.275042 0.275042)
							(end -0.3048 0.2032)
						)
						(arc
							(start -0.3048 -0.2032)
							(mid -0.275042 -0.275042)
							(end -0.2032 -0.3048)
						)
						(arc
							(start 0.2032 -0.3048)
							(mid 0.275042 -0.275042)
							(end 0.3048 -0.2032)
						)
					)
					(width 0)
					(fill yes)
				)
			)
		)
	)
	(footprint ""
		(layer "B.Cu")
		(at 30.430216 -232.33888)
		(property "Reference" "R507"
			(at 0 0 0)
			(layer "B.SilkS")
			(hide yes)
			(effects
				(font
					(size 1.27 1.27)
				)
				(justify mirror)
			)
		)
		(property "Value" "0R2J-2-GP"
			(at -0.064008 -3.993896 0)
			(unlocked yes)
			(layer "B.Fab")
			(hide yes)
			(effects
				(font
					(size 1.016 1.016)
					(thickness 0.1524)
				)
				(justify mirror)
			)
		)
		(property "Device Type" "R402H16"
			(at -0.064008 -5.517896 0)
			(unlocked yes)
			(layer "B.Fab")
			(hide yes)
			(effects
				(font
					(size 1.016 1.016)
					(thickness 0.1524)
				)
				(justify mirror)
			)
		)
		(duplicate_pad_numbers_are_jumpers no)
		(fp_line
			(start -0.508 -0.9398)
			(end 0.508 -0.9398)
			(stroke
				(width 0.1524)
				(type default)
			)
			(layer "B.SilkS")
		)
		(fp_line
			(start 0.508 -0.9398)
			(end 0.508 0.9398)
			(stroke
				(width 0.1524)
				(type default)
			)
			(layer "B.SilkS")
		)
		(fp_rect
			(start 0.508 0.9398)
			(end -0.508 -0.9398)
			(stroke
				(width 0)
				(type default)
			)
			(fill no)
			(layer "B.CrtYd")
		)
		(fp_rect
			(start 0.508 0.9398)
			(end -0.508 -0.9398)
			(stroke
				(width 0)
				(type default)
			)
			(fill no)
			(layer "B.Fab")
		)
		(pad "1" smd custom
			(at 0 -0.4445 180)
			(size 0.1397 0.1397)
			(layers "B.Cu" "B.Mask" "B.Paste")
			(net "SAS_HDD_PWR5_PCIE")
			(options
				(clearance outline)
				(anchor circle)
			)
			(primitives
				(gr_poly
					(pts
						(arc
							(start -0.1778 0.2794)
							(mid -0.249642 0.249642)
							(end -0.2794 0.1778)
						)
						(arc
							(start -0.2794 -0.1778)
							(mid -0.249642 -0.249642)
							(end -0.1778 -0.2794)
						)
						(arc
							(start 0.1778 -0.2794)
							(mid 0.249642 -0.249642)
							(end 0.2794 -0.1778)
						)
						(arc
							(start 0.2794 0.1778)
							(mid 0.249642 0.249642)
							(end 0.1778 0.2794)
						)
					)
					(width 0)
					(fill yes)
				)
			)
		)
		(pad "2" smd custom
			(at 0 0.4445 180)
			(size 0.1397 0.1397)
			(layers "B.Cu" "B.Mask" "B.Paste")
			(net "SAS_HDD_PWR5")
			(options
				(clearance outline)
				(anchor circle)
			)
			(primitives
				(gr_poly
					(pts
						(arc
							(start -0.1778 0.2794)
							(mid -0.249642 0.249642)
							(end -0.2794 0.1778)
						)
						(arc
							(start -0.2794 -0.1778)
							(mid -0.249642 -0.249642)
							(end -0.1778 -0.2794)
						)
						(arc
							(start 0.1778 -0.2794)
							(mid 0.249642 -0.249642)
							(end 0.2794 -0.1778)
						)
						(arc
							(start 0.2794 0.1778)
							(mid 0.249642 0.249642)
							(end 0.1778 0.2794)
						)
					)
					(width 0)
					(fill yes)
				)
			)
		)
	)
	(footprint ""
		(layer "B.Cu")
		(at 101.86797 -96.901 -90)
		(property "Reference" "STP86"
			(at 0 0 90)
			(layer "B.SilkS")
			(hide yes)
			(effects
				(font
					(size 1.27 1.27)
				)
				(justify mirror)
			)
		)
		(property "Value" "TPAD28"
			(at -0.0127 -1.8034 270)
			(unlocked yes)
			(layer "B.Fab")
			(hide yes)
			(effects
				(font
					(size 1.016 1.016)
					(thickness 0.1524)
				)
				(justify mirror)
			)
		)
		(property "Device Type" "TPAD28"
			(at -0.0127 -3.3274 270)
			(unlocked yes)
			(layer "B.Fab")
			(hide yes)
			(effects
				(font
					(size 1.016 1.016)
					(thickness 0.1524)
				)
				(justify mirror)
			)
		)
		(duplicate_pad_numbers_are_jumpers no)
		(fp_poly
			(pts
				(arc
					(start 0 -0.3556)
					(mid 0 0.3556)
					(end 0 -0.3556)
				)
			)
			(stroke
				(width 0)
				(type default)
			)
			(fill no)
			(layer "B.CrtYd")
		)
		(fp_poly
			(pts
				(arc
					(start 0 -0.6096)
					(mid 0 0.6096)
					(end 0 -0.6096)
				)
			)
			(stroke
				(width 0)
				(type default)
			)
			(fill no)
			(layer "B.Fab")
		)
		(pad "1" smd circle
			(at 0 0 90)
			(size 0.7112 0.7112)
			(layers "B.Cu" "B.Mask" "B.Paste")
			(net "EXP_PWM_OUT0")
		)
	)
	(footprint ""
		(layer "B.Cu")
		(at 123.171966 -33.528)
		(property "Reference" "SC934"
			(at 0 0 0)
			(layer "B.SilkS")
			(hide yes)
			(effects
				(font
					(size 1.27 1.27)
				)
				(justify mirror)
			)
		)
		(property "Value" "SCD1U6D3V1KX-GP"
			(at 2.8321 -1.7399 0)
			(unlocked yes)
			(layer "B.Fab")
			(hide yes)
			(effects
				(font
					(size 1.016 1.016)
					(thickness 0.1524)
				)
				(justify mirror)
			)
		)
		(property "Device Type" "C0201H13"
			(at 2.8321 -3.2639 0)
			(unlocked yes)
			(layer "B.Fab")
			(hide yes)
			(effects
				(font
					(size 1.016 1.016)
					(thickness 0.1524)
				)
				(justify mirror)
			)
		)
		(duplicate_pad_numbers_are_jumpers no)
		(fp_rect
			(start 0.2794 0.6477)
			(end -0.2794 -0.6477)
			(stroke
				(width 0)
				(type default)
			)
			(fill no)
			(layer "B.CrtYd")
		)
		(fp_rect
			(start 0.2794 0.6477)
			(end -0.2794 -0.6477)
			(stroke
				(width 0)
				(type default)
			)
			(fill no)
			(layer "B.Fab")
		)
		(pad "1" smd custom
			(at 0 -0.2794 180)
			(size 0.0762 0.0762)
			(layers "B.Cu" "B.Mask" "B.Paste")
			(net "PLL_VDD")
			(options
				(clearance outline)
				(anchor circle)
			)
			(primitives
				(gr_poly
					(pts
						(arc
							(start 0.1524 0.127)
							(mid 0.137521 0.162921)
							(end 0.1016 0.1778)
						)
						(arc
							(start -0.1016 0.1778)
							(mid -0.137521 0.162921)
							(end -0.1524 0.127)
						)
						(arc
							(start -0.1524 -0.127)
							(mid -0.137521 -0.162921)
							(end -0.1016 -0.1778)
						)
						(arc
							(start 0.1016 -0.1778)
							(mid 0.137521 -0.162921)
							(end 0.1524 -0.127)
						)
					)
					(width 0)
					(fill yes)
				)
			)
		)
		(pad "2" smd custom
			(at 0 0.2794 180)
			(size 0.0762 0.0762)
			(layers "B.Cu" "B.Mask" "B.Paste")
			(net "GND")
			(options
				(clearance outline)
				(anchor circle)
			)
			(primitives
				(gr_poly
					(pts
						(arc
							(start 0.1524 0.127)
							(mid 0.137521 0.162921)
							(end 0.1016 0.1778)
						)
						(arc
							(start -0.1016 0.1778)
							(mid -0.137521 0.162921)
							(end -0.1524 0.127)
						)
						(arc
							(start -0.1524 -0.127)
							(mid -0.137521 -0.162921)
							(end -0.1016 -0.1778)
						)
						(arc
							(start 0.1016 -0.1778)
							(mid 0.137521 -0.162921)
							(end 0.1524 -0.127)
						)
					)
					(width 0)
					(fill yes)
				)
			)
		)
	)
	(footprint ""
		(layer "B.Cu")
		(at 18.281904 -100.400866)
		(property "Reference" "C135"
			(at 0 0 0)
			(layer "B.SilkS")
			(hide yes)
			(effects
				(font
					(size 1.27 1.27)
				)
				(justify mirror)
			)
		)
		(property "Value" "SCD01U50V2KX-1GP"
			(at -1.1811 -2.7051 0)
			(unlocked yes)
			(layer "B.Fab")
			(hide yes)
			(effects
				(font
					(size 1.016 1.016)
					(thickness 0.1524)
				)
				(justify mirror)
			)
		)
		(property "Device Type" "C402H22"
			(at -1.1811 -4.2291 0)
			(unlocked yes)
			(layer "B.Fab")
			(hide yes)
			(effects
				(font
					(size 1.016 1.016)
					(thickness 0.1524)
				)
				(justify mirror)
			)
		)
		(duplicate_pad_numbers_are_jumpers no)
		(fp_rect
			(start 0.4318 0.9525)
			(end -0.4318 -0.9525)
			(stroke
				(width 0)
				(type default)
			)
			(fill no)
			(layer "B.CrtYd")
		)
		(fp_rect
			(start 0.4318 0.9525)
			(end -0.4318 -0.9525)
			(stroke
				(width 0)
				(type default)
			)
			(fill no)
			(layer "B.Fab")
		)
		(pad "1" smd custom
			(at 0 -0.4445 180)
			(size 0.1524 0.1524)
			(layers "B.Cu" "B.Mask" "B.Paste")
			(net "IOC_SAS_RX_P7")
			(options
				(clearance outline)
				(anchor circle)
			)
			(primitives
				(gr_poly
					(pts
						(arc
							(start 0.3048 0.2032)
							(mid 0.275042 0.275042)
							(end 0.2032 0.3048)
						)
						(arc
							(start -0.2032 0.3048)
							(mid -0.275042 0.275042)
							(end -0.3048 0.2032)
						)
						(arc
							(start -0.3048 -0.2032)
							(mid -0.275042 -0.275042)
							(end -0.2032 -0.3048)
						)
						(arc
							(start 0.2032 -0.3048)
							(mid 0.275042 -0.275042)
							(end 0.3048 -0.2032)
						)
					)
					(width 0)
					(fill yes)
				)
			)
		)
		(pad "2" smd custom
			(at 0 0.4445 180)
			(size 0.1524 0.1524)
			(layers "B.Cu" "B.Mask" "B.Paste")
			(net "SAS_EXT_CONN_RX19_P")
			(options
				(clearance outline)
				(anchor circle)
			)
			(primitives
				(gr_poly
					(pts
						(arc
							(start 0.3048 0.2032)
							(mid 0.275042 0.275042)
							(end 0.2032 0.3048)
						)
						(arc
							(start -0.2032 0.3048)
							(mid -0.275042 0.275042)
							(end -0.3048 0.2032)
						)
						(arc
							(start -0.3048 -0.2032)
							(mid -0.275042 -0.275042)
							(end -0.2032 -0.3048)
						)
						(arc
							(start 0.2032 -0.3048)
							(mid 0.275042 -0.275042)
							(end 0.3048 -0.2032)
						)
					)
					(width 0)
					(fill yes)
				)
			)
		)
	)
	(footprint ""
		(layer "B.Cu")
		(at 124.403612 -218.821 -90)
		(property "Reference" "SR909"
			(at 0 0 90)
			(layer "B.SilkS")
			(hide yes)
			(effects
				(font
					(size 1.27 1.27)
				)
				(justify mirror)
			)
		)
		(property "Value" "4K7R2F-GP"
			(at -0.064008 -3.993896 270)
			(unlocked yes)
			(layer "B.Fab")
			(hide yes)
			(effects
				(font
					(size 1.016 1.016)
					(thickness 0.1524)
				)
				(justify mirror)
			)
		)
		(property "Device Type" "R402H16"
			(at -0.064008 -5.517896 270)
			(unlocked yes)
			(layer "B.Fab")
			(hide yes)
			(effects
				(font
					(size 1.016 1.016)
					(thickness 0.1524)
				)
				(justify mirror)
			)
		)
		(duplicate_pad_numbers_are_jumpers no)
		(fp_line
			(start -0.508 -0.9398)
			(end 0.508 -0.9398)
			(stroke
				(width 0.1524)
				(type default)
			)
			(layer "B.SilkS")
		)
		(fp_line
			(start 0.508 -0.9398)
			(end 0.508 0.9398)
			(stroke
				(width 0.1524)
				(type default)
			)
			(layer "B.SilkS")
		)
		(fp_rect
			(start 0.508 0.9398)
			(end -0.508 -0.9398)
			(stroke
				(width 0)
				(type default)
			)
			(fill no)
			(layer "B.CrtYd")
		)
		(fp_rect
			(start 0.508 0.9398)
			(end -0.508 -0.9398)
			(stroke
				(width 0)
				(type default)
			)
			(fill no)
			(layer "B.Fab")
		)
		(pad "1" smd custom
			(at 0 -0.4445 90)
			(size 0.1397 0.1397)
			(layers "B.Cu" "B.Mask" "B.Paste")
			(net "P1V26_STBY")
			(options
				(clearance outline)
				(anchor circle)
			)
			(primitives
				(gr_poly
					(pts
						(arc
							(start -0.1778 0.2794)
							(mid -0.249642 0.249642)
							(end -0.2794 0.1778)
						)
						(arc
							(start -0.2794 -0.1778)
							(mid -0.249642 -0.249642)
							(end -0.1778 -0.2794)
						)
						(arc
							(start 0.1778 -0.2794)
							(mid 0.249642 -0.249642)
							(end 0.2794 -0.1778)
						)
						(arc
							(start 0.2794 0.1778)
							(mid 0.249642 0.249642)
							(end 0.1778 0.2794)
						)
					)
					(width 0)
					(fill yes)
				)
			)
		)
		(pad "2" smd custom
			(at 0 0.4445 90)
			(size 0.1397 0.1397)
			(layers "B.Cu" "B.Mask" "B.Paste")
			(net "REDV_PD#")
			(options
				(clearance outline)
				(anchor circle)
			)
			(primitives
				(gr_poly
					(pts
						(arc
							(start -0.1778 0.2794)
							(mid -0.249642 0.249642)
							(end -0.2794 0.1778)
						)
						(arc
							(start -0.2794 -0.1778)
							(mid -0.249642 -0.249642)
							(end -0.1778 -0.2794)
						)
						(arc
							(start 0.1778 -0.2794)
							(mid 0.249642 -0.249642)
							(end 0.2794 -0.1778)
						)
						(arc
							(start 0.2794 0.1778)
							(mid 0.249642 0.249642)
							(end 0.1778 0.2794)
						)
					)
					(width 0)
					(fill yes)
				)
			)
		)
	)
)
